# S9S_MB_2U (Grand Teton) — schematic netlist excerpt (pin names and nets, part order shuffled) for the footprints in the layout excerpt that follows; sources: Cadence DE-HDL packaged netlist, KiCad conversion of 03242023_DA0F0TMBIJ0_F0T_Motherboard_J_brd_V01_OCP.brd

R582  Q_RES  33.2 1% CHIP  pkg 0402LF  page 241 : A = SMB_SML0_3V3AUX_SDA ; B = SMB_SML0_3V3AUX_PCH_SDA
R4205  Q_RES  1K 1% CHIP  pkg 0402LF  page 170 : A = U271_1_ADD0 ; B = GND
R3634  Q_RES  0.01 1% CHIP  pkg 2512LF  page 172 : A = P3V3_M2_0 ; B = P3V3

(kicad_pcb
	(version 20260206)
	(generator "pcbnew")
	(generator_version "10.0")
	(general
		(thickness 1.6)
		(legacy_teardrops no)
	)
	(paper "A4")
	(title_block
		(title "03242023_DA0F0TMBIJ0_F0T_Motherboard_J_brd_V01_OCP.brd")
		(comment 1 "Grand Teton / footprints 1893-1895 of 6105")
	)
	(layers
		(0 "F.Cu" signal "TOP")
		(4 "In1.Cu" signal "GND")
		(6 "In2.Cu" signal "IN1")
		(8 "In3.Cu" signal "GND1")
		(10 "In4.Cu" signal "IN2")
		(12 "In5.Cu" signal "GND2")
		(14 "In6.Cu" signal "IN3")
		(16 "In7.Cu" signal "GND3")
		(18 "In8.Cu" signal "VCC")
		(20 "In9.Cu" signal "VCC1")
		(22 "In10.Cu" signal "GND4")
		(24 "In11.Cu" signal "IN4")
		(26 "In12.Cu" signal "GND5")
		(28 "In13.Cu" signal "IN5")
		(30 "In14.Cu" signal "GND6")
		(32 "In15.Cu" signal "IN6")
		(34 "In16.Cu" signal "GND7")
		(2 "B.Cu" signal "BOTTOM")
		(9 "F.Adhes" user "F.Adhesive")
		(11 "B.Adhes" user "B.Adhesive")
		(13 "F.Paste" user "Package Geometry/Pastemask Top")
		(15 "B.Paste" user "Package Geometry/Pastemask Bottom")
		(5 "F.SilkS" user "Ref Des/Silkscreen Top")
		(7 "B.SilkS" user "Ref Des/Silkscreen Bottom")
		(1 "F.Mask" user "Board Geometry/Soldermask Top")
		(3 "B.Mask" user "Board Geometry/Soldermask Bottom")
		(17 "Dwgs.User" user "User.Drawings")
		(19 "Cmts.User" user "User.Comments")
		(21 "Eco1.User" user "User.Eco1")
		(23 "Eco2.User" user "User.Eco2")
		(25 "Edge.Cuts" user "Board Geometry/Outline")
		(27 "Margin" user)
		(31 "F.CrtYd" user "Package Geometry/Place Bound Top")
		(29 "B.CrtYd" user "Package Geometry/Place Bound Bottom")
		(35 "F.Fab" user "Ref Des/Assembly Top")
		(33 "B.Fab" user "Ref Des/Assembly Bottom")
	)
	(footprint ""
		(layer "F.Cu")
		(at 7.42188 -59.019948 180)
		(property "Reference" "R582"
			(at 0 0 180)
			(layer "F.SilkS")
			(hide yes)
			(effects
				(font
					(size 1.27 1.27)
				)
			)
		)
		(property "Value" ""
			(at 0 0 180)
			(layer "F.Fab")
			(effects
				(font
					(size 1.27 1.27)
				)
			)
		)
		(duplicate_pad_numbers_are_jumpers no)
		(fp_line
			(start 0.7874 0.4064)
			(end -0.7874 0.4064)
			(stroke
				(width 0.1524)
				(type default)
			)
			(layer "F.SilkS")
		)
		(fp_line
			(start 0.7874 -0.4064)
			(end 0.7874 0.4064)
			(stroke
				(width 0.1524)
				(type default)
			)
			(layer "F.SilkS")
		)
		(fp_line
			(start -0.7874 0.4064)
			(end -0.7874 -0.4064)
			(stroke
				(width 0.1524)
				(type default)
			)
			(layer "F.SilkS")
		)
		(fp_line
			(start -0.7874 -0.4064)
			(end 0.7874 -0.4064)
			(stroke
				(width 0.1524)
				(type default)
			)
			(layer "F.SilkS")
		)
		(fp_line
			(start 0.67945 0.3048)
			(end 0.120396 0.3048)
			(stroke
				(width 0.1)
				(type default)
			)
			(layer "F.Fab")
		)
		(fp_line
			(start 0.67945 -0.3048)
			(end 0.67945 0.3048)
			(stroke
				(width 0.1)
				(type default)
			)
			(layer "F.Fab")
		)
		(fp_line
			(start 0.12065 -0.2794)
			(end 0.12065 -0.3048)
			(stroke
				(width 0.1)
				(type default)
			)
			(layer "F.Fab")
		)
		(fp_line
			(start 0.12065 -0.3048)
			(end 0.67945 -0.3048)
			(stroke
				(width 0.1)
				(type default)
			)
			(layer "F.Fab")
		)
		(fp_line
			(start 0.120396 0.3048)
			(end 0.120396 0.2794)
			(stroke
				(width 0.1)
				(type default)
			)
			(layer "F.Fab")
		)
		(fp_line
			(start 0.120396 0.2794)
			(end -0.12065 0.2794)
			(stroke
				(width 0.1)
				(type default)
			)
			(layer "F.Fab")
		)
		(fp_line
			(start -0.12065 0.3048)
			(end -0.67945 0.3048)
			(stroke
				(width 0.1)
				(type default)
			)
			(layer "F.Fab")
		)
		(fp_line
			(start -0.12065 0.2794)
			(end -0.12065 0.3048)
			(stroke
				(width 0.1)
				(type default)
			)
			(layer "F.Fab")
		)
		(fp_line
			(start -0.12065 -0.2794)
			(end 0.12065 -0.2794)
			(stroke
				(width 0.1)
				(type default)
			)
			(layer "F.Fab")
		)
		(fp_line
			(start -0.12065 -0.305054)
			(end -0.12065 -0.2794)
			(stroke
				(width 0.1)
				(type default)
			)
			(layer "F.Fab")
		)
		(fp_line
			(start -0.67945 0.3048)
			(end -0.67945 -0.305054)
			(stroke
				(width 0.1)
				(type default)
			)
			(layer "F.Fab")
		)
		(fp_line
			(start -0.67945 -0.305054)
			(end -0.12065 -0.305054)
			(stroke
				(width 0.1)
				(type default)
			)
			(layer "F.Fab")
		)
		(pad "1" smd circle
			(at -0.40005 0 180)
			(size 0 0)
			(layers "F.Cu" "F.Mask" "F.Paste")
			(net "SMB_SML0_3V3AUX_SDA")
		)
		(pad "2" smd circle
			(at 0.40005 0 180)
			(size 0 0)
			(layers "F.Cu" "F.Mask" "F.Paste")
			(net "SMB_SML0_3V3AUX_PCH_SDA")
		)
	)
	(footprint ""
		(layer "F.Cu")
		(at 162.622484 -53.267864 90)
		(property "Reference" "R3634"
			(at 0 0 90)
			(layer "F.SilkS")
			(hide yes)
			(effects
				(font
					(size 1.27 1.27)
				)
			)
		)
		(property "Value" ""
			(at 0 0 90)
			(layer "F.Fab")
			(effects
				(font
					(size 1.27 1.27)
				)
			)
		)
		(duplicate_pad_numbers_are_jumpers no)
		(fp_line
			(start 4.0386 -1.7526)
			(end 4.0386 1.7526)
			(stroke
				(width 0.1524)
				(type default)
			)
			(layer "F.SilkS")
		)
		(fp_line
			(start -4.0386 -1.7526)
			(end 4.0386 -1.7526)
			(stroke
				(width 0.1524)
				(type default)
			)
			(layer "F.SilkS")
		)
		(fp_line
			(start 4.0386 1.7526)
			(end -4.0386 1.7526)
			(stroke
				(width 0.1524)
				(type default)
			)
			(layer "F.SilkS")
		)
		(fp_line
			(start -4.0386 1.7526)
			(end -4.0386 -1.7526)
			(stroke
				(width 0.1524)
				(type default)
			)
			(layer "F.SilkS")
		)
		(fp_line
			(start 4.0386 -1.7526)
			(end 4.0386 1.7526)
			(stroke
				(width 0.1)
				(type default)
			)
			(layer "F.Fab")
		)
		(fp_line
			(start -4.0386 -1.7526)
			(end 4.0386 -1.7526)
			(stroke
				(width 0.1)
				(type default)
			)
			(layer "F.Fab")
		)
		(fp_line
			(start 4.0386 1.7526)
			(end -4.0386 1.7526)
			(stroke
				(width 0.1)
				(type default)
			)
			(layer "F.Fab")
		)
		(fp_line
			(start -4.0386 1.7526)
			(end -4.0386 -1.7526)
			(stroke
				(width 0.1)
				(type default)
			)
			(layer "F.Fab")
		)
		(pad "1" smd rect
			(at -3.1115 0 90)
			(size 1.524 3.2004)
			(layers "F.Cu" "F.Mask" "F.Paste")
			(net "P3V3_M2_0")
		)
		(pad "2" smd rect
			(at 3.1115 0 90)
			(size 1.524 3.2004)
			(layers "F.Cu" "F.Mask" "F.Paste")
			(net "P3V3")
		)
	)
	(footprint ""
		(layer "F.Cu")
		(at 300.728634 -16.715994)
		(property "Reference" "R4205"
			(at 0 0 0)
			(layer "F.SilkS")
			(hide yes)
			(effects
				(font
					(size 1.27 1.27)
				)
			)
		)
		(property "Value" ""
			(at 0 0 0)
			(layer "F.Fab")
			(effects
				(font
					(size 1.27 1.27)
				)
			)
		)
		(duplicate_pad_numbers_are_jumpers no)
		(fp_line
			(start -0.7874 -0.4064)
			(end 0.7874 -0.4064)
			(stroke
				(width 0.1524)
				(type default)
			)
			(layer "F.SilkS")
		)
		(fp_line
			(start -0.7874 0.4064)
			(end -0.7874 -0.4064)
			(stroke
				(width 0.1524)
				(type default)
			)
			(layer "F.SilkS")
		)
		(fp_line
			(start 0.7874 -0.4064)
			(end 0.7874 0.4064)
			(stroke
				(width 0.1524)
				(type default)
			)
			(layer "F.SilkS")
		)
		(fp_line
			(start 0.7874 0.4064)
			(end -0.7874 0.4064)
			(stroke
				(width 0.1524)
				(type default)
			)
			(layer "F.SilkS")
		)
		(fp_line
			(start -0.67945 -0.305054)
			(end -0.12065 -0.305054)
			(stroke
				(width 0.1)
				(type default)
			)
			(layer "F.Fab")
		)
		(fp_line
			(start -0.67945 0.3048)
			(end -0.67945 -0.305054)
			(stroke
				(width 0.1)
				(type default)
			)
			(layer "F.Fab")
		)
		(fp_line
			(start -0.12065 -0.305054)
			(end -0.12065 -0.2794)
			(stroke
				(width 0.1)
				(type default)
			)
			(layer "F.Fab")
		)
		(fp_line
			(start -0.12065 -0.2794)
			(end 0.12065 -0.2794)
			(stroke
				(width 0.1)
				(type default)
			)
			(layer "F.Fab")
		)
		(fp_line
			(start -0.12065 0.2794)
			(end -0.12065 0.3048)
			(stroke
				(width 0.1)
				(type default)
			)
			(layer "F.Fab")
		)
		(fp_line
			(start -0.12065 0.3048)
			(end -0.67945 0.3048)
			(stroke
				(width 0.1)
				(type default)
			)
			(layer "F.Fab")
		)
		(fp_line
			(start 0.120396 0.2794)
			(end -0.12065 0.2794)
			(stroke
				(width 0.1)
				(type default)
			)
			(layer "F.Fab")
		)
		(fp_line
			(start 0.120396 0.3048)
			(end 0.120396 0.2794)
			(stroke
				(width 0.1)
				(type default)
			)
			(layer "F.Fab")
		)
		(fp_line
			(start 0.12065 -0.3048)
			(end 0.67945 -0.3048)
			(stroke
				(width 0.1)
				(type default)
			)
			(layer "F.Fab")
		)
		(fp_line
			(start 0.12065 -0.2794)
			(end 0.12065 -0.3048)
			(stroke
				(width 0.1)
				(type default)
			)
			(layer "F.Fab")
		)
		(fp_line
			(start 0.67945 -0.3048)
			(end 0.67945 0.3048)
			(stroke
				(width 0.1)
				(type default)
			)
			(layer "F.Fab")
		)
		(fp_line
			(start 0.67945 0.3048)
			(end 0.120396 0.3048)
			(stroke
				(width 0.1)
				(type default)
			)
			(layer "F.Fab")
		)
		(pad "1" smd circle
			(at -0.40005 0)
			(size 0 0)
			(layers "F.Cu" "F.Mask" "F.Paste")
			(net "U271_1_ADD0")
		)
		(pad "2" smd circle
			(at 0.40005 0)
			(size 0 0)
			(layers "F.Cu" "F.Mask" "F.Paste")
			(net "GND")
		)
	)
)
